(kicad_pcb
	(version 20260206)
	(generator "pcbnew")
	(generator_version "10.0")
	(general
		(thickness 1.6)
		(legacy_teardrops no)
	)
	(paper "A4")
	(title_block
		(title "01162023_DA0F0TEBIF0_F0T_Expander_BD_F_brd_V02_OCP.brd")
		(comment 1 "Grand Teton / footprints 2001-2007 of 9728")
	)
	(layers
		(0 "F.Cu" signal "TOP")
		(4 "In1.Cu" signal "GND")
		(6 "In2.Cu" signal "VCC")
		(8 "In3.Cu" signal "VCC1")
		(10 "In4.Cu" signal "GND1")
		(12 "In5.Cu" signal "IN1")
		(14 "In6.Cu" signal "GND2")
		(16 "In7.Cu" signal "IN2")
		(18 "In8.Cu" signal "GND3")
		(20 "In9.Cu" signal "IN3")
		(22 "In10.Cu" signal "GND4")
		(24 "In11.Cu" signal "IN4")
		(26 "In12.Cu" signal "GND5")
		(28 "In13.Cu" signal "IN5")
		(30 "In14.Cu" signal "GND6")
		(32 "In15.Cu" signal "IN6")
		(34 "In16.Cu" signal "GND7")
		(2 "B.Cu" signal "BOTTOM")
		(9 "F.Adhes" user "F.Adhesive")
		(11 "B.Adhes" user "B.Adhesive")
		(13 "F.Paste" user "Package Geometry/Pastemask Top")
		(15 "B.Paste" user "Package Geometry/Pastemask Bottom")
		(5 "F.SilkS" user "Ref Des/Silkscreen Top")
		(7 "B.SilkS" user "Ref Des/Silkscreen Bottom")
		(1 "F.Mask" user "Board Geometry/Soldermask Top")
		(3 "B.Mask" user "Board Geometry/Soldermask Bottom")
		(17 "Dwgs.User" user "User.Drawings")
		(19 "Cmts.User" user "User.Comments")
		(21 "Eco1.User" user "User.Eco1")
		(23 "Eco2.User" user "User.Eco2")
		(25 "Edge.Cuts" user "Board Geometry/Outline")
		(27 "Margin" user)
		(31 "F.CrtYd" user "Package Geometry/Place Bound Top")
		(29 "B.CrtYd" user "Package Geometry/Place Bound Bottom")
		(35 "F.Fab" user "Ref Des/Assembly Top")
		(33 "B.Fab" user "Ref Des/Assembly Bottom")
	)
	(footprint ""
		(layer "F.Cu")
		(at 7.189216 -16.135858 180)
		(property "Reference" "C3873"
			(at 0 0 180)
			(layer "F.SilkS")
			(hide yes)
			(effects
				(font
					(size 1.27 1.27)
				)
			)
		)
		(property "Value" ""
			(at 0 0 180)
			(layer "F.Fab")
			(effects
				(font
					(size 1.27 1.27)
				)
			)
		)
		(duplicate_pad_numbers_are_jumpers no)
		(fp_line
			(start 0.7874 0.4064)
			(end -0.7874 0.4064)
			(stroke
				(width 0.1524)
				(type default)
			)
			(layer "F.SilkS")
		)
		(fp_line
			(start 0.7874 -0.4064)
			(end 0.7874 0.4064)
			(stroke
				(width 0.1524)
				(type default)
			)
			(layer "F.SilkS")
		)
		(fp_line
			(start -0.7874 0.4064)
			(end -0.7874 -0.4064)
			(stroke
				(width 0.1524)
				(type default)
			)
			(layer "F.SilkS")
		)
		(fp_line
			(start -0.7874 -0.4064)
			(end 0.7874 -0.4064)
			(stroke
				(width 0.1524)
				(type default)
			)
			(layer "F.SilkS")
		)
		(fp_line
			(start 0.67945 0.3048)
			(end 0.120396 0.3048)
			(stroke
				(width 0.1)
				(type default)
			)
			(layer "F.Fab")
		)
		(fp_line
			(start 0.67945 -0.3048)
			(end 0.67945 0.3048)
			(stroke
				(width 0.1)
				(type default)
			)
			(layer "F.Fab")
		)
		(fp_line
			(start 0.12065 -0.2794)
			(end 0.12065 -0.3048)
			(stroke
				(width 0.1)
				(type default)
			)
			(layer "F.Fab")
		)
		(fp_line
			(start 0.12065 -0.3048)
			(end 0.67945 -0.3048)
			(stroke
				(width 0.1)
				(type default)
			)
			(layer "F.Fab")
		)
		(fp_line
			(start 0.120396 0.3048)
			(end 0.120396 0.2794)
			(stroke
				(width 0.1)
				(type default)
			)
			(layer "F.Fab")
		)
		(fp_line
			(start 0.120396 0.2794)
			(end -0.12065 0.2794)
			(stroke
				(width 0.1)
				(type default)
			)
			(layer "F.Fab")
		)
		(fp_line
			(start -0.12065 0.3048)
			(end -0.67945 0.3048)
			(stroke
				(width 0.1)
				(type default)
			)
			(layer "F.Fab")
		)
		(fp_line
			(start -0.12065 0.2794)
			(end -0.12065 0.3048)
			(stroke
				(width 0.1)
				(type default)
			)
			(layer "F.Fab")
		)
		(fp_line
			(start -0.12065 -0.2794)
			(end 0.12065 -0.2794)
			(stroke
				(width 0.1)
				(type default)
			)
			(layer "F.Fab")
		)
		(fp_line
			(start -0.12065 -0.305054)
			(end -0.12065 -0.2794)
			(stroke
				(width 0.1)
				(type default)
			)
			(layer "F.Fab")
		)
		(fp_line
			(start -0.67945 0.3048)
			(end -0.67945 -0.305054)
			(stroke
				(width 0.1)
				(type default)
			)
			(layer "F.Fab")
		)
		(fp_line
			(start -0.67945 -0.305054)
			(end -0.12065 -0.305054)
			(stroke
				(width 0.1)
				(type default)
			)
			(layer "F.Fab")
		)
		(pad "1" smd circle
			(at -0.40005 0 180)
			(size 0 0)
			(layers "F.Cu" "F.Mask" "F.Paste")
			(net "P12V_SSD0")
		)
		(pad "2" smd circle
			(at 0.40005 0 180)
			(size 0 0)
			(layers "F.Cu" "F.Mask" "F.Paste")
			(net "GND")
		)
	)
	(footprint ""
		(layer "F.Cu")
		(at 224.686622 -107.056682)
		(property "Reference" "PC626"
			(at 0 0 0)
			(layer "F.SilkS")
			(hide yes)
			(effects
				(font
					(size 1.27 1.27)
				)
			)
		)
		(property "Value" ""
			(at 0 0 0)
			(layer "F.Fab")
			(effects
				(font
					(size 1.27 1.27)
				)
			)
		)
		(duplicate_pad_numbers_are_jumpers no)
		(fp_line
			(start -1.524 -0.762)
			(end 1.524 -0.762)
			(stroke
				(width 0.1524)
				(type default)
			)
			(layer "F.SilkS")
		)
		(fp_line
			(start -1.524 0.762)
			(end -1.524 -0.762)
			(stroke
				(width 0.1524)
				(type default)
			)
			(layer "F.SilkS")
		)
		(fp_line
			(start 1.524 -0.762)
			(end 1.524 0.762)
			(stroke
				(width 0.1524)
				(type default)
			)
			(layer "F.SilkS")
		)
		(fp_line
			(start 1.524 0.762)
			(end -1.524 0.762)
			(stroke
				(width 0.1524)
				(type default)
			)
			(layer "F.SilkS")
		)
		(fp_line
			(start -1.1049 -0.724916)
			(end -1.1049 0.724916)
			(stroke
				(width 0.1)
				(type default)
			)
			(layer "F.Fab")
		)
		(fp_line
			(start -1.1049 0.724916)
			(end 1.1049 0.724916)
			(stroke
				(width 0.1)
				(type default)
			)
			(layer "F.Fab")
		)
		(fp_line
			(start 1.1049 -0.724916)
			(end -1.1049 -0.724916)
			(stroke
				(width 0.1)
				(type default)
			)
			(layer "F.Fab")
		)
		(fp_line
			(start 1.1049 0.724916)
			(end 1.1049 -0.724916)
			(stroke
				(width 0.1)
				(type default)
			)
			(layer "F.Fab")
		)
		(pad "1" smd rect
			(at -0.889 0 180)
			(size 1.016 1.27)
			(layers "F.Cu" "F.Mask" "F.Paste")
			(net "P12V_NIC3_R")
		)
		(pad "2" smd rect
			(at 0.889 0 180)
			(size 1.016 1.27)
			(layers "F.Cu" "F.Mask" "F.Paste")
			(net "GND")
		)
	)
	(footprint ""
		(layer "F.Cu")
		(at 366.507776 -152.71115 90)
		(property "Reference" "R750"
			(at 0 0 90)
			(layer "F.SilkS")
			(hide yes)
			(effects
				(font
					(size 1.27 1.27)
				)
			)
		)
		(property "Value" ""
			(at 0 0 90)
			(layer "F.Fab")
			(effects
				(font
					(size 1.27 1.27)
				)
			)
		)
		(duplicate_pad_numbers_are_jumpers no)
		(fp_line
			(start 0.7874 -0.4064)
			(end 0.7874 0.4064)
			(stroke
				(width 0.1524)
				(type default)
			)
			(layer "F.SilkS")
		)
		(fp_line
			(start -0.7874 -0.4064)
			(end 0.7874 -0.4064)
			(stroke
				(width 0.1524)
				(type default)
			)
			(layer "F.SilkS")
		)
		(fp_line
			(start 0.7874 0.4064)
			(end -0.7874 0.4064)
			(stroke
				(width 0.1524)
				(type default)
			)
			(layer "F.SilkS")
		)
		(fp_line
			(start -0.7874 0.4064)
			(end -0.7874 -0.4064)
			(stroke
				(width 0.1524)
				(type default)
			)
			(layer "F.SilkS")
		)
		(fp_line
			(start -0.12065 -0.305054)
			(end -0.12065 -0.2794)
			(stroke
				(width 0.1)
				(type default)
			)
			(layer "F.Fab")
		)
		(fp_line
			(start -0.67945 -0.305054)
			(end -0.12065 -0.305054)
			(stroke
				(width 0.1)
				(type default)
			)
			(layer "F.Fab")
		)
		(fp_line
			(start 0.67945 -0.3048)
			(end 0.67945 0.3048)
			(stroke
				(width 0.1)
				(type default)
			)
			(layer "F.Fab")
		)
		(fp_line
			(start 0.12065 -0.3048)
			(end 0.67945 -0.3048)
			(stroke
				(width 0.1)
				(type default)
			)
			(layer "F.Fab")
		)
		(fp_line
			(start 0.12065 -0.2794)
			(end 0.12065 -0.3048)
			(stroke
				(width 0.1)
				(type default)
			)
			(layer "F.Fab")
		)
		(fp_line
			(start -0.12065 -0.2794)
			(end 0.12065 -0.2794)
			(stroke
				(width 0.1)
				(type default)
			)
			(layer "F.Fab")
		)
		(fp_line
			(start 0.120396 0.2794)
			(end -0.12065 0.2794)
			(stroke
				(width 0.1)
				(type default)
			)
			(layer "F.Fab")
		)
		(fp_line
			(start -0.12065 0.2794)
			(end -0.12065 0.3048)
			(stroke
				(width 0.1)
				(type default)
			)
			(layer "F.Fab")
		)
		(fp_line
			(start 0.67945 0.3048)
			(end 0.120396 0.3048)
			(stroke
				(width 0.1)
				(type default)
			)
			(layer "F.Fab")
		)
		(fp_line
			(start 0.120396 0.3048)
			(end 0.120396 0.2794)
			(stroke
				(width 0.1)
				(type default)
			)
			(layer "F.Fab")
		)
		(fp_line
			(start -0.12065 0.3048)
			(end -0.67945 0.3048)
			(stroke
				(width 0.1)
				(type default)
			)
			(layer "F.Fab")
		)
		(fp_line
			(start -0.67945 0.3048)
			(end -0.67945 -0.305054)
			(stroke
				(width 0.1)
				(type default)
			)
			(layer "F.Fab")
		)
		(pad "1" smd circle
			(at -0.40005 0 90)
			(size 0 0)
			(layers "F.Cu" "F.Mask" "F.Paste")
			(net "NIC6_ADC_ALERT_N")
		)
		(pad "2" smd circle
			(at 0.40005 0 90)
			(size 0 0)
			(layers "F.Cu" "F.Mask" "F.Paste")
			(net "NIC_ADC_ALERT_N")
		)
	)
	(footprint ""
		(layer "F.Cu")
		(at 179.570634 -137.848848 180)
		(property "Reference" "R159"
			(at 0 0 180)
			(layer "F.SilkS")
			(hide yes)
			(effects
				(font
					(size 1.27 1.27)
				)
			)
		)
		(property "Value" ""
			(at 0 0 180)
			(layer "F.Fab")
			(effects
				(font
					(size 1.27 1.27)
				)
			)
		)
		(duplicate_pad_numbers_are_jumpers no)
		(fp_line
			(start 0.7874 0.4064)
			(end -0.7874 0.4064)
			(stroke
				(width 0.1524)
				(type default)
			)
			(layer "F.SilkS")
		)
		(fp_line
			(start 0.7874 -0.4064)
			(end 0.7874 0.4064)
			(stroke
				(width 0.1524)
				(type default)
			)
			(layer "F.SilkS")
		)
		(fp_line
			(start -0.7874 0.4064)
			(end -0.7874 -0.4064)
			(stroke
				(width 0.1524)
				(type default)
			)
			(layer "F.SilkS")
		)
		(fp_line
			(start -0.7874 -0.4064)
			(end 0.7874 -0.4064)
			(stroke
				(width 0.1524)
				(type default)
			)
			(layer "F.SilkS")
		)
		(fp_line
			(start 0.67945 0.3048)
			(end 0.120396 0.3048)
			(stroke
				(width 0.1)
				(type default)
			)
			(layer "F.Fab")
		)
		(fp_line
			(start 0.67945 -0.3048)
			(end 0.67945 0.3048)
			(stroke
				(width 0.1)
				(type default)
			)
			(layer "F.Fab")
		)
		(fp_line
			(start 0.12065 -0.2794)
			(end 0.12065 -0.3048)
			(stroke
				(width 0.1)
				(type default)
			)
			(layer "F.Fab")
		)
		(fp_line
			(start 0.12065 -0.3048)
			(end 0.67945 -0.3048)
			(stroke
				(width 0.1)
				(type default)
			)
			(layer "F.Fab")
		)
		(fp_line
			(start 0.120396 0.3048)
			(end 0.120396 0.2794)
			(stroke
				(width 0.1)
				(type default)
			)
			(layer "F.Fab")
		)
		(fp_line
			(start 0.120396 0.2794)
			(end -0.12065 0.2794)
			(stroke
				(width 0.1)
				(type default)
			)
			(layer "F.Fab")
		)
		(fp_line
			(start -0.12065 0.3048)
			(end -0.67945 0.3048)
			(stroke
				(width 0.1)
				(type default)
			)
			(layer "F.Fab")
		)
		(fp_line
			(start -0.12065 0.2794)
			(end -0.12065 0.3048)
			(stroke
				(width 0.1)
				(type default)
			)
			(layer "F.Fab")
		)
		(fp_line
			(start -0.12065 -0.2794)
			(end 0.12065 -0.2794)
			(stroke
				(width 0.1)
				(type default)
			)
			(layer "F.Fab")
		)
		(fp_line
			(start -0.12065 -0.305054)
			(end -0.12065 -0.2794)
			(stroke
				(width 0.1)
				(type default)
			)
			(layer "F.Fab")
		)
		(fp_line
			(start -0.67945 0.3048)
			(end -0.67945 -0.305054)
			(stroke
				(width 0.1)
				(type default)
			)
			(layer "F.Fab")
		)
		(fp_line
			(start -0.67945 -0.305054)
			(end -0.12065 -0.305054)
			(stroke
				(width 0.1)
				(type default)
			)
			(layer "F.Fab")
		)
		(pad "1" smd circle
			(at -0.40005 0 180)
			(size 0 0)
			(layers "F.Cu" "F.Mask" "F.Paste")
			(net "PRSNTB1_NIC3_N")
		)
		(pad "2" smd circle
			(at 0.40005 0 180)
			(size 0 0)
			(layers "F.Cu" "F.Mask" "F.Paste")
			(net "P3V3_AUX")
		)
	)
	(footprint ""
		(layer "F.Cu")
		(at 80.53959 -138.661648 180)
		(property "Reference" "R90"
			(at 0 0 180)
			(layer "F.SilkS")
			(hide yes)
			(effects
				(font
					(size 1.27 1.27)
				)
			)
		)
		(property "Value" ""
			(at 0 0 180)
			(layer "F.Fab")
			(effects
				(font
					(size 1.27 1.27)
				)
			)
		)
		(duplicate_pad_numbers_are_jumpers no)
		(fp_line
			(start 0.7874 0.4064)
			(end -0.7874 0.4064)
			(stroke
				(width 0.1524)
				(type default)
			)
			(layer "F.SilkS")
		)
		(fp_line
			(start 0.7874 -0.4064)
			(end 0.7874 0.4064)
			(stroke
				(width 0.1524)
				(type default)
			)
			(layer "F.SilkS")
		)
		(fp_line
			(start -0.7874 0.4064)
			(end -0.7874 -0.4064)
			(stroke
				(width 0.1524)
				(type default)
			)
			(layer "F.SilkS")
		)
		(fp_line
			(start -0.7874 -0.4064)
			(end 0.7874 -0.4064)
			(stroke
				(width 0.1524)
				(type default)
			)
			(layer "F.SilkS")
		)
		(fp_line
			(start 0.67945 0.3048)
			(end 0.120396 0.3048)
			(stroke
				(width 0.1)
				(type default)
			)
			(layer "F.Fab")
		)
		(fp_line
			(start 0.67945 -0.3048)
			(end 0.67945 0.3048)
			(stroke
				(width 0.1)
				(type default)
			)
			(layer "F.Fab")
		)
		(fp_line
			(start 0.12065 -0.2794)
			(end 0.12065 -0.3048)
			(stroke
				(width 0.1)
				(type default)
			)
			(layer "F.Fab")
		)
		(fp_line
			(start 0.12065 -0.3048)
			(end 0.67945 -0.3048)
			(stroke
				(width 0.1)
				(type default)
			)
			(layer "F.Fab")
		)
		(fp_line
			(start 0.120396 0.3048)
			(end 0.120396 0.2794)
			(stroke
				(width 0.1)
				(type default)
			)
			(layer "F.Fab")
		)
		(fp_line
			(start 0.120396 0.2794)
			(end -0.12065 0.2794)
			(stroke
				(width 0.1)
				(type default)
			)
			(layer "F.Fab")
		)
		(fp_line
			(start -0.12065 0.3048)
			(end -0.67945 0.3048)
			(stroke
				(width 0.1)
				(type default)
			)
			(layer "F.Fab")
		)
		(fp_line
			(start -0.12065 0.2794)
			(end -0.12065 0.3048)
			(stroke
				(width 0.1)
				(type default)
			)
			(layer "F.Fab")
		)
		(fp_line
			(start -0.12065 -0.2794)
			(end 0.12065 -0.2794)
			(stroke
				(width 0.1)
				(type default)
			)
			(layer "F.Fab")
		)
		(fp_line
			(start -0.12065 -0.305054)
			(end -0.12065 -0.2794)
			(stroke
				(width 0.1)
				(type default)
			)
			(layer "F.Fab")
		)
		(fp_line
			(start -0.67945 0.3048)
			(end -0.67945 -0.305054)
			(stroke
				(width 0.1)
				(type default)
			)
			(layer "F.Fab")
		)
		(fp_line
			(start -0.67945 -0.305054)
			(end -0.12065 -0.305054)
			(stroke
				(width 0.1)
				(type default)
			)
			(layer "F.Fab")
		)
		(pad "1" smd circle
			(at -0.40005 0 180)
			(size 0 0)
			(layers "F.Cu" "F.Mask" "F.Paste")
			(net "PRSNT_NIC1_N")
		)
		(pad "2" smd circle
			(at 0.40005 0 180)
			(size 0 0)
			(layers "F.Cu" "F.Mask" "F.Paste")
			(net "PRSNTB0_NIC1_N")
		)
	)
	(footprint ""
		(layer "F.Cu")
		(at 143.0528 -262.649208 90)
		(property "Reference" "C3228"
			(at 0 0 90)
			(layer "F.SilkS")
			(hide yes)
			(effects
				(font
					(size 1.27 1.27)
				)
			)
		)
		(property "Value" ""
			(at 0 0 90)
			(layer "F.Fab")
			(effects
				(font
					(size 1.27 1.27)
				)
			)
		)
		(duplicate_pad_numbers_are_jumpers no)
		(fp_line
			(start 0.299974 -0.150114)
			(end 0.299974 0.150114)
			(stroke
				(width 0.1)
				(type default)
			)
			(layer "F.Fab")
		)
		(fp_line
			(start -0.299974 -0.150114)
			(end 0.299974 -0.150114)
			(stroke
				(width 0.1)
				(type default)
			)
			(layer "F.Fab")
		)
		(fp_line
			(start 0.299974 0.150114)
			(end -0.299974 0.150114)
			(stroke
				(width 0.1)
				(type default)
			)
			(layer "F.Fab")
		)
		(fp_line
			(start -0.299974 0.150114)
			(end -0.299974 -0.150114)
			(stroke
				(width 0.1)
				(type default)
			)
			(layer "F.Fab")
		)
		(pad "1" smd rect
			(at -0.2667 0 90)
			(size 0.3048 0.381)
			(layers "F.Cu" "F.Mask" "F.Paste")
			(net "P1V8_PLL0_PEX1")
		)
		(pad "2" smd rect
			(at 0.2667 0 90)
			(size 0.3048 0.381)
			(layers "F.Cu" "F.Mask" "F.Paste")
			(net "GND")
		)
	)
	(footprint ""
		(layer "F.Cu")
		(at 101.829362 -385.605274 -90)
		(property "Reference" "R5444"
			(at 0 0 270)
			(layer "F.SilkS")
			(hide yes)
			(effects
				(font
					(size 1.27 1.27)
				)
			)
		)
		(property "Value" ""
			(at 0 0 270)
			(layer "F.Fab")
			(effects
				(font
					(size 1.27 1.27)
				)
			)
		)
		(duplicate_pad_numbers_are_jumpers no)
		(fp_line
			(start -0.007874 0.4064)
			(end -0.7874 0.4064)
			(stroke
				(width 0.1524)
				(type default)
			)
			(layer "F.SilkS")
		)
		(fp_line
			(start -0.7874 -0.4064)
			(end 0.7874 -0.4064)
			(stroke
				(width 0.1524)
				(type default)
			)
			(layer "F.SilkS")
		)
		(fp_line
			(start 0.7874 -0.4064)
			(end 0.7874 0.4064)
			(stroke
				(width 0.1524)
				(type default)
			)
			(layer "F.SilkS")
		)
		(fp_line
			(start -0.67945 0.3048)
			(end -0.67945 -0.305054)
			(stroke
				(width 0.1)
				(type default)
			)
			(layer "F.Fab")
		)
		(fp_line
			(start -0.12065 0.3048)
			(end -0.67945 0.3048)
			(stroke
				(width 0.1)
				(type default)
			)
			(layer "F.Fab")
		)
		(fp_line
			(start 0.120396 0.3048)
			(end 0.120396 0.2794)
			(stroke
				(width 0.1)
				(type default)
			)
			(layer "F.Fab")
		)
		(fp_line
			(start 0.67945 0.3048)
			(end 0.120396 0.3048)
			(stroke
				(width 0.1)
				(type default)
			)
			(layer "F.Fab")
		)
		(fp_line
			(start -0.12065 0.2794)
			(end -0.12065 0.3048)
			(stroke
				(width 0.1)
				(type default)
			)
			(layer "F.Fab")
		)
		(fp_line
			(start 0.120396 0.2794)
			(end -0.12065 0.2794)
			(stroke
				(width 0.1)
				(type default)
			)
			(layer "F.Fab")
		)
		(fp_line
			(start -0.12065 -0.2794)
			(end 0.12065 -0.2794)
			(stroke
				(width 0.1)
				(type default)
			)
			(layer "F.Fab")
		)
		(fp_line
			(start 0.12065 -0.2794)
			(end 0.12065 -0.3048)
			(stroke
				(width 0.1)
				(type default)
			)
			(layer "F.Fab")
		)
		(fp_line
			(start 0.12065 -0.3048)
			(end 0.67945 -0.3048)
			(stroke
				(width 0.1)
				(type default)
			)
			(layer "F.Fab")
		)
		(fp_line
			(start 0.67945 -0.3048)
			(end 0.67945 0.3048)
			(stroke
				(width 0.1)
				(type default)
			)
			(layer "F.Fab")
		)
		(fp_line
			(start -0.67945 -0.305054)
			(end -0.12065 -0.305054)
			(stroke
				(width 0.1)
				(type default)
			)
			(layer "F.Fab")
		)
		(fp_line
			(start -0.12065 -0.305054)
			(end -0.12065 -0.2794)
			(stroke
				(width 0.1)
				(type default)
			)
			(layer "F.Fab")
		)
		(pad "1" smd rect
			(at -0.40005 0 90)
			(size 0.4572 0.508)
			(layers "F.Cu" "F.Mask" "F.Paste")
			(net "USB2_MB_BMC_R_DP")
		)
		(pad "2" smd rect
			(at 0.40005 0 90)
			(size 0.4572 0.508)
			(layers "F.Cu" "F.Mask" "F.Paste")
			(net "USB2_MB_BMC_DP")
		)
	)
)
